(kicad_pcb
	(version 20260206)
	(generator "pcbnew")
	(generator_version "10.0")
	(general
		(thickness 1.6)
		(legacy_teardrops no)
	)
	(paper "A4")
	(title_block
		(title "panther-plus-userver — 13130-1b_20150205.brd")
		(comment 1 "Honey Badger (Wiwynn) / footprints 841-848 of 1509")
	)
	(layers
		(0 "F.Cu" signal "TOP")
		(4 "In1.Cu" signal "L2")
		(6 "In2.Cu" signal "L3")
		(8 "In3.Cu" signal "L4")
		(10 "In4.Cu" signal "L5")
		(12 "In5.Cu" signal "L6")
		(14 "In6.Cu" signal "L7")
		(16 "In7.Cu" signal "L8")
		(18 "In8.Cu" signal "L9")
		(20 "In9.Cu" signal "L10")
		(22 "In10.Cu" signal "L11")
		(2 "B.Cu" signal "BOTTOM")
		(9 "F.Adhes" user "F.Adhesive")
		(11 "B.Adhes" user "B.Adhesive")
		(13 "F.Paste" user "Package Geometry/Pastemask Top")
		(15 "B.Paste" user "Package Geometry/Pastemask Bottom")
		(5 "F.SilkS" user "Ref Des/Silkscreen Top")
		(7 "B.SilkS" user "Ref Des/Silkscreen Bottom")
		(1 "F.Mask" user "Board Geometry/Soldermask Top")
		(3 "B.Mask" user "Board Geometry/Soldermask Bottom")
		(17 "Dwgs.User" user "User.Drawings")
		(19 "Cmts.User" user "User.Comments")
		(21 "Eco1.User" user "User.Eco1")
		(23 "Eco2.User" user "User.Eco2")
		(25 "Edge.Cuts" user "Board Geometry/Outline")
		(27 "Margin" user)
		(31 "F.CrtYd" user "Package Geometry/Place Bound Top")
		(29 "B.CrtYd" user "Package Geometry/Place Bound Bottom")
		(35 "F.Fab" user "Ref Des/Assembly Top")
		(33 "B.Fab" user "Ref Des/Assembly Bottom")
	)
	(footprint ""
		(layer "B.Cu")
		(at 71.501 -34.417 -90)
		(property "Reference" "R335"
			(at 0 0 90)
			(layer "B.SilkS")
			(hide yes)
			(effects
				(font
					(size 1.27 1.27)
				)
				(justify mirror)
			)
		)
		(property "Value" "11KR2F-L-GP"
			(at -0.064008 -3.993896 270)
			(unlocked yes)
			(layer "B.Fab")
			(hide yes)
			(effects
				(font
					(size 1.016 1.016)
					(thickness 0.1524)
				)
				(justify mirror)
			)
		)
		(property "Device Type" "R402H16"
			(at -0.064008 -5.517896 270)
			(unlocked yes)
			(layer "B.Fab")
			(hide yes)
			(effects
				(font
					(size 1.016 1.016)
					(thickness 0.1524)
				)
				(justify mirror)
			)
		)
		(duplicate_pad_numbers_are_jumpers no)
		(fp_rect
			(start 0.381 0.8382)
			(end -0.381 -0.8382)
			(stroke
				(width 0)
				(type default)
			)
			(fill no)
			(layer "B.CrtYd")
		)
		(fp_rect
			(start 0.381 0.8382)
			(end -0.381 -0.8382)
			(stroke
				(width 0)
				(type default)
			)
			(fill no)
			(layer "B.Fab")
		)
		(pad "1" smd custom
			(at 0 -0.4318 90)
			(size 0.127 0.127)
			(layers "B.Cu" "B.Mask" "B.Paste")
			(net "P3V3_RTC")
			(options
				(clearance outline)
				(anchor circle)
			)
			(primitives
				(gr_poly
					(pts
						(arc
							(start -0.2032 0.2794)
							(mid -0.239121 0.264521)
							(end -0.254 0.2286)
						)
						(arc
							(start -0.254 -0.2286)
							(mid -0.239121 -0.264521)
							(end -0.2032 -0.2794)
						)
						(arc
							(start 0.2032 -0.2794)
							(mid 0.239121 -0.264521)
							(end 0.254 -0.2286)
						)
						(arc
							(start 0.254 0.2286)
							(mid 0.239121 0.264521)
							(end 0.2032 0.2794)
						)
					)
					(width 0)
					(fill yes)
				)
			)
		)
		(pad "2" smd custom
			(at 0 0.4318 90)
			(size 0.127 0.127)
			(layers "B.Cu" "B.Mask" "B.Paste")
			(net "SRTCRST_BUF_IN#")
			(options
				(clearance outline)
				(anchor circle)
			)
			(primitives
				(gr_poly
					(pts
						(arc
							(start -0.2032 0.2794)
							(mid -0.239121 0.264521)
							(end -0.254 0.2286)
						)
						(arc
							(start -0.254 -0.2286)
							(mid -0.239121 -0.264521)
							(end -0.2032 -0.2794)
						)
						(arc
							(start 0.2032 -0.2794)
							(mid 0.239121 -0.264521)
							(end 0.254 -0.2286)
						)
						(arc
							(start 0.254 0.2286)
							(mid 0.239121 0.264521)
							(end 0.2032 0.2794)
						)
					)
					(width 0)
					(fill yes)
				)
			)
		)
	)
	(footprint ""
		(layer "B.Cu")
		(at 93.599 -26.924 90)
		(property "Reference" "C226"
			(at 0 0 90)
			(layer "B.SilkS")
			(hide yes)
			(effects
				(font
					(size 1.27 1.27)
				)
				(justify mirror)
			)
		)
		(property "Value" "SC1U10V2KX-1GP"
			(at -1.1811 -2.7051 90)
			(unlocked yes)
			(layer "B.Fab")
			(hide yes)
			(effects
				(font
					(size 1.016 1.016)
					(thickness 0.1524)
				)
				(justify mirror)
			)
		)
		(property "Device Type" "C402H22"
			(at -1.1811 -4.2291 90)
			(unlocked yes)
			(layer "B.Fab")
			(hide yes)
			(effects
				(font
					(size 1.016 1.016)
					(thickness 0.1524)
				)
				(justify mirror)
			)
		)
		(duplicate_pad_numbers_are_jumpers no)
		(fp_rect
			(start 0.381 0.7366)
			(end -0.381 -0.7366)
			(stroke
				(width 0)
				(type default)
			)
			(fill no)
			(layer "B.CrtYd")
		)
		(fp_rect
			(start 0.381 0.7366)
			(end -0.381 -0.7366)
			(stroke
				(width 0)
				(type default)
			)
			(fill no)
			(layer "B.Fab")
		)
		(pad "1" smd custom
			(at 0 -0.4572 270)
			(size 0.1143 0.1143)
			(layers "B.Cu" "B.Mask" "B.Paste")
			(net "P1V0")
			(options
				(clearance outline)
				(anchor circle)
			)
			(primitives
				(gr_poly
					(pts
						(arc
							(start -0.254 0.1778)
							(mid -0.239121 0.213721)
							(end -0.2032 0.2286)
						)
						(arc
							(start 0.2032 0.2286)
							(mid 0.239121 0.213721)
							(end 0.254 0.1778)
						)
						(arc
							(start 0.254 -0.1778)
							(mid 0.239121 -0.213721)
							(end 0.2032 -0.2286)
						)
						(arc
							(start -0.2032 -0.2286)
							(mid -0.239121 -0.213721)
							(end -0.254 -0.1778)
						)
					)
					(width 0)
					(fill yes)
				)
			)
		)
		(pad "2" smd custom
			(at 0 0.4572 270)
			(size 0.1143 0.1143)
			(layers "B.Cu" "B.Mask" "B.Paste")
			(net "GND")
			(options
				(clearance outline)
				(anchor circle)
			)
			(primitives
				(gr_poly
					(pts
						(arc
							(start -0.254 0.1778)
							(mid -0.239121 0.213721)
							(end -0.2032 0.2286)
						)
						(arc
							(start 0.2032 0.2286)
							(mid 0.239121 0.213721)
							(end 0.254 0.1778)
						)
						(arc
							(start 0.254 -0.1778)
							(mid 0.239121 -0.213721)
							(end 0.2032 -0.2286)
						)
						(arc
							(start -0.2032 -0.2286)
							(mid -0.239121 -0.213721)
							(end -0.254 -0.1778)
						)
					)
					(width 0)
					(fill yes)
				)
			)
		)
	)
	(footprint ""
		(layer "B.Cu")
		(at 101.981 -33.290002 90)
		(property "Reference" "C218"
			(at 0 0 90)
			(layer "B.SilkS")
			(hide yes)
			(effects
				(font
					(size 1.27 1.27)
				)
				(justify mirror)
			)
		)
		(property "Value" "SC1U10V2KX-1GP"
			(at -1.1811 -2.7051 90)
			(unlocked yes)
			(layer "B.Fab")
			(hide yes)
			(effects
				(font
					(size 1.016 1.016)
					(thickness 0.1524)
				)
				(justify mirror)
			)
		)
		(property "Device Type" "C402H22"
			(at -1.1811 -4.2291 90)
			(unlocked yes)
			(layer "B.Fab")
			(hide yes)
			(effects
				(font
					(size 1.016 1.016)
					(thickness 0.1524)
				)
				(justify mirror)
			)
		)
		(duplicate_pad_numbers_are_jumpers no)
		(fp_rect
			(start 0.381 0.7366)
			(end -0.381 -0.7366)
			(stroke
				(width 0)
				(type default)
			)
			(fill no)
			(layer "B.CrtYd")
		)
		(fp_rect
			(start 0.381 0.7366)
			(end -0.381 -0.7366)
			(stroke
				(width 0)
				(type default)
			)
			(fill no)
			(layer "B.Fab")
		)
		(pad "1" smd custom
			(at 0 -0.4572 270)
			(size 0.1143 0.1143)
			(layers "B.Cu" "B.Mask" "B.Paste")
			(net "P1V0")
			(options
				(clearance outline)
				(anchor circle)
			)
			(primitives
				(gr_poly
					(pts
						(arc
							(start -0.254 0.1778)
							(mid -0.239121 0.213721)
							(end -0.2032 0.2286)
						)
						(arc
							(start 0.2032 0.2286)
							(mid 0.239121 0.213721)
							(end 0.254 0.1778)
						)
						(arc
							(start 0.254 -0.1778)
							(mid 0.239121 -0.213721)
							(end 0.2032 -0.2286)
						)
						(arc
							(start -0.2032 -0.2286)
							(mid -0.239121 -0.213721)
							(end -0.254 -0.1778)
						)
					)
					(width 0)
					(fill yes)
				)
			)
		)
		(pad "2" smd custom
			(at 0 0.4572 270)
			(size 0.1143 0.1143)
			(layers "B.Cu" "B.Mask" "B.Paste")
			(net "GND")
			(options
				(clearance outline)
				(anchor circle)
			)
			(primitives
				(gr_poly
					(pts
						(arc
							(start -0.254 0.1778)
							(mid -0.239121 0.213721)
							(end -0.2032 0.2286)
						)
						(arc
							(start 0.2032 0.2286)
							(mid 0.239121 0.213721)
							(end 0.254 0.1778)
						)
						(arc
							(start 0.254 -0.1778)
							(mid 0.239121 -0.213721)
							(end 0.2032 -0.2286)
						)
						(arc
							(start -0.2032 -0.2286)
							(mid -0.239121 -0.213721)
							(end -0.254 -0.1778)
						)
					)
					(width 0)
					(fill yes)
				)
			)
		)
	)
	(footprint ""
		(layer "B.Cu")
		(at 106.0831 -44.608242 90)
		(property "Reference" "R303"
			(at 0 0 90)
			(layer "B.SilkS")
			(hide yes)
			(effects
				(font
					(size 1.27 1.27)
				)
				(justify mirror)
			)
		)
		(property "Value" "162R2F-GP"
			(at -0.064008 -3.993896 90)
			(unlocked yes)
			(layer "B.Fab")
			(hide yes)
			(effects
				(font
					(size 1.016 1.016)
					(thickness 0.1524)
				)
				(justify mirror)
			)
		)
		(property "Device Type" "R402H16"
			(at -0.064008 -5.517896 90)
			(unlocked yes)
			(layer "B.Fab")
			(hide yes)
			(effects
				(font
					(size 1.016 1.016)
					(thickness 0.1524)
				)
				(justify mirror)
			)
		)
		(duplicate_pad_numbers_are_jumpers no)
		(fp_rect
			(start 0.381 0.8382)
			(end -0.381 -0.8382)
			(stroke
				(width 0)
				(type default)
			)
			(fill no)
			(layer "B.CrtYd")
		)
		(fp_rect
			(start 0.381 0.8382)
			(end -0.381 -0.8382)
			(stroke
				(width 0)
				(type default)
			)
			(fill no)
			(layer "B.Fab")
		)
		(pad "1" smd custom
			(at 0 -0.4318 270)
			(size 0.127 0.127)
			(layers "B.Cu" "B.Mask" "B.Paste")
			(net "M_A_ODTPU")
			(options
				(clearance outline)
				(anchor circle)
			)
			(primitives
				(gr_poly
					(pts
						(arc
							(start -0.2032 0.2794)
							(mid -0.239121 0.264521)
							(end -0.254 0.2286)
						)
						(arc
							(start -0.254 -0.2286)
							(mid -0.239121 -0.264521)
							(end -0.2032 -0.2794)
						)
						(arc
							(start 0.2032 -0.2794)
							(mid 0.239121 -0.264521)
							(end 0.254 -0.2286)
						)
						(arc
							(start 0.254 0.2286)
							(mid 0.239121 0.264521)
							(end 0.2032 0.2794)
						)
					)
					(width 0)
					(fill yes)
				)
			)
		)
		(pad "2" smd custom
			(at 0 0.4318 270)
			(size 0.127 0.127)
			(layers "B.Cu" "B.Mask" "B.Paste")
			(net "GND")
			(options
				(clearance outline)
				(anchor circle)
			)
			(primitives
				(gr_poly
					(pts
						(arc
							(start -0.2032 0.2794)
							(mid -0.239121 0.264521)
							(end -0.254 0.2286)
						)
						(arc
							(start -0.254 -0.2286)
							(mid -0.239121 -0.264521)
							(end -0.2032 -0.2794)
						)
						(arc
							(start 0.2032 -0.2794)
							(mid 0.239121 -0.264521)
							(end 0.254 -0.2286)
						)
						(arc
							(start 0.254 0.2286)
							(mid 0.239121 0.264521)
							(end 0.2032 0.2794)
						)
					)
					(width 0)
					(fill yes)
				)
			)
		)
	)
	(footprint ""
		(layer "B.Cu")
		(at 130.175 -14.987778 180)
		(property "Reference" "C355"
			(at 0 0 0)
			(layer "B.SilkS")
			(hide yes)
			(effects
				(font
					(size 1.27 1.27)
				)
				(justify mirror)
			)
		)
		(property "Value" "SC1U6D3V3KX-2GP"
			(at 0.0254 -2.0193 180)
			(unlocked yes)
			(layer "B.Fab")
			(hide yes)
			(effects
				(font
					(size 1.016 1.016)
					(thickness 0.1524)
				)
				(justify mirror)
			)
		)
		(property "Device Type" "C603H36"
			(at 0.0254 -3.5433 180)
			(unlocked yes)
			(layer "B.Fab")
			(hide yes)
			(effects
				(font
					(size 1.016 1.016)
					(thickness 0.1524)
				)
				(justify mirror)
			)
		)
		(duplicate_pad_numbers_are_jumpers no)
		(fp_line
			(start 0.4064 0)
			(end -0.4064 0)
			(stroke
				(width 0.2286)
				(type default)
			)
			(layer "B.SilkS")
		)
		(fp_rect
			(start 0.635 1.1811)
			(end -0.635 -1.1811)
			(stroke
				(width 0)
				(type default)
			)
			(fill no)
			(layer "B.CrtYd")
		)
		(fp_rect
			(start 0.635 1.1811)
			(end -0.635 -1.1811)
			(stroke
				(width 0)
				(type default)
			)
			(fill no)
			(layer "B.Fab")
		)
		(pad "1" smd custom
			(at 0 -0.6604)
			(size 0.19685 0.19685)
			(layers "B.Cu" "B.Mask" "B.Paste")
			(net "DDR3_M_B_VREF_DQ1")
			(options
				(clearance outline)
				(anchor circle)
			)
			(primitives
				(gr_poly
					(pts
						(arc
							(start 0.508 0.2921)
							(mid 0.478242 0.363942)
							(end 0.4064 0.3937)
						)
						(arc
							(start -0.4064 0.3937)
							(mid -0.478242 0.363942)
							(end -0.508 0.2921)
						)
						(arc
							(start -0.508 -0.2921)
							(mid -0.478242 -0.363942)
							(end -0.4064 -0.3937)
						)
						(arc
							(start 0.4064 -0.3937)
							(mid 0.478242 -0.363942)
							(end 0.508 -0.2921)
						)
					)
					(width 0)
					(fill yes)
				)
			)
		)
		(pad "2" smd custom
			(at 0 0.6604)
			(size 0.19685 0.19685)
			(layers "B.Cu" "B.Mask" "B.Paste")
			(net "GND")
			(options
				(clearance outline)
				(anchor circle)
			)
			(primitives
				(gr_poly
					(pts
						(arc
							(start 0.508 0.2921)
							(mid 0.478242 0.363942)
							(end 0.4064 0.3937)
						)
						(arc
							(start -0.4064 0.3937)
							(mid -0.478242 0.363942)
							(end -0.508 0.2921)
						)
						(arc
							(start -0.508 -0.2921)
							(mid -0.478242 -0.363942)
							(end -0.4064 -0.3937)
						)
						(arc
							(start 0.4064 -0.3937)
							(mid 0.478242 -0.363942)
							(end 0.508 -0.2921)
						)
					)
					(width 0)
					(fill yes)
				)
			)
		)
	)
	(footprint ""
		(layer "B.Cu")
		(at 14.859 -48.133)
		(property "Reference" "C250"
			(at 0 0 0)
			(layer "B.SilkS")
			(hide yes)
			(effects
				(font
					(size 1.27 1.27)
				)
				(justify mirror)
			)
		)
		(property "Value" "SC1U6D3V2KX-GP"
			(at -1.8923 -1.2065 0)
			(unlocked yes)
			(layer "B.Fab")
			(hide yes)
			(effects
				(font
					(size 1.016 1.016)
					(thickness 0.1524)
				)
				(justify mirror)
			)
		)
		(property "Device Type" "C402H22"
			(at -1.8923 -2.7305 0)
			(unlocked yes)
			(layer "B.Fab")
			(hide yes)
			(effects
				(font
					(size 1.016 1.016)
					(thickness 0.1524)
				)
				(justify mirror)
			)
		)
		(duplicate_pad_numbers_are_jumpers no)
		(fp_rect
			(start 0.381 0.7366)
			(end -0.381 -0.7366)
			(stroke
				(width 0)
				(type default)
			)
			(fill no)
			(layer "B.CrtYd")
		)
		(fp_rect
			(start 0.381 0.7366)
			(end -0.381 -0.7366)
			(stroke
				(width 0)
				(type default)
			)
			(fill no)
			(layer "B.Fab")
		)
		(pad "1" smd custom
			(at 0 -0.4572 180)
			(size 0.1143 0.1143)
			(layers "B.Cu" "B.Mask" "B.Paste")
			(net "P3V3")
			(options
				(clearance outline)
				(anchor circle)
			)
			(primitives
				(gr_poly
					(pts
						(arc
							(start -0.254 0.1778)
							(mid -0.239121 0.213721)
							(end -0.2032 0.2286)
						)
						(arc
							(start 0.2032 0.2286)
							(mid 0.239121 0.213721)
							(end 0.254 0.1778)
						)
						(arc
							(start 0.254 -0.1778)
							(mid 0.239121 -0.213721)
							(end 0.2032 -0.2286)
						)
						(arc
							(start -0.2032 -0.2286)
							(mid -0.239121 -0.213721)
							(end -0.254 -0.1778)
						)
					)
					(width 0)
					(fill yes)
				)
			)
		)
		(pad "2" smd custom
			(at 0 0.4572 180)
			(size 0.1143 0.1143)
			(layers "B.Cu" "B.Mask" "B.Paste")
			(net "GND")
			(options
				(clearance outline)
				(anchor circle)
			)
			(primitives
				(gr_poly
					(pts
						(arc
							(start -0.254 0.1778)
							(mid -0.239121 0.213721)
							(end -0.2032 0.2286)
						)
						(arc
							(start 0.2032 0.2286)
							(mid 0.239121 0.213721)
							(end 0.254 0.1778)
						)
						(arc
							(start 0.254 -0.1778)
							(mid 0.239121 -0.213721)
							(end 0.2032 -0.2286)
						)
						(arc
							(start -0.2032 -0.2286)
							(mid -0.239121 -0.213721)
							(end -0.254 -0.1778)
						)
					)
					(width 0)
					(fill yes)
				)
			)
		)
	)
	(footprint ""
		(layer "B.Cu")
		(at 76.962 -19.7358 90)
		(property "Reference" "PR225"
			(at 0 0 90)
			(layer "B.SilkS")
			(hide yes)
			(effects
				(font
					(size 1.27 1.27)
				)
				(justify mirror)
			)
		)
		(property "Value" "0R3J-6-GP"
			(at 0.0254 -2.5146 90)
			(unlocked yes)
			(layer "B.Fab")
			(hide yes)
			(effects
				(font
					(size 1.016 1.016)
					(thickness 0.1524)
				)
				(justify mirror)
			)
		)
		(property "Device Type" "R603H22"
			(at 0.0254 -4.0386 90)
			(unlocked yes)
			(layer "B.Fab")
			(hide yes)
			(effects
				(font
					(size 1.016 1.016)
					(thickness 0.1524)
				)
				(justify mirror)
			)
		)
		(duplicate_pad_numbers_are_jumpers no)
		(fp_line
			(start 0.2032 0)
			(end 0.4191 0)
			(stroke
				(width 0.2032)
				(type default)
			)
			(layer "B.SilkS")
		)
		(fp_line
			(start -0.4318 0)
			(end -0.2032 0)
			(stroke
				(width 0.2032)
				(type default)
			)
			(layer "B.SilkS")
		)
		(fp_rect
			(start 0.635 1.1811)
			(end -0.635 -1.1811)
			(stroke
				(width 0)
				(type default)
			)
			(fill no)
			(layer "B.CrtYd")
		)
		(fp_rect
			(start 0.635 1.1811)
			(end -0.635 -1.1811)
			(stroke
				(width 0)
				(type default)
			)
			(fill no)
			(layer "B.Fab")
		)
		(pad "1" smd custom
			(at 0 -0.6604 270)
			(size 0.19685 0.19685)
			(layers "B.Cu" "B.Mask" "B.Paste")
			(net "P1V8_STBY")
			(options
				(clearance outline)
				(anchor circle)
			)
			(primitives
				(gr_poly
					(pts
						(arc
							(start 0.508 0.2921)
							(mid 0.478242 0.363942)
							(end 0.4064 0.3937)
						)
						(arc
							(start -0.4064 0.3937)
							(mid -0.478242 0.363942)
							(end -0.508 0.2921)
						)
						(arc
							(start -0.508 -0.2921)
							(mid -0.478242 -0.363942)
							(end -0.4064 -0.3937)
						)
						(arc
							(start 0.4064 -0.3937)
							(mid 0.478242 -0.363942)
							(end 0.508 -0.2921)
						)
					)
					(width 0)
					(fill yes)
				)
			)
		)
		(pad "2" smd custom
			(at 0 0.6604 270)
			(size 0.19685 0.19685)
			(layers "B.Cu" "B.Mask" "B.Paste")
			(net "TPS74801_P1V35_IN")
			(options
				(clearance outline)
				(anchor circle)
			)
			(primitives
				(gr_poly
					(pts
						(arc
							(start 0.508 0.2921)
							(mid 0.478242 0.363942)
							(end 0.4064 0.3937)
						)
						(arc
							(start -0.4064 0.3937)
							(mid -0.478242 0.363942)
							(end -0.508 0.2921)
						)
						(arc
							(start -0.508 -0.2921)
							(mid -0.478242 -0.363942)
							(end -0.4064 -0.3937)
						)
						(arc
							(start 0.4064 -0.3937)
							(mid 0.478242 -0.363942)
							(end 0.508 -0.2921)
						)
					)
					(width 0)
					(fill yes)
				)
			)
		)
	)
	(footprint ""
		(layer "B.Cu")
		(at 20.701 -59.944 180)
		(property "Reference" "PC3"
			(at 0 0 0)
			(layer "B.SilkS")
			(hide yes)
			(effects
				(font
					(size 1.27 1.27)
				)
				(justify mirror)
			)
		)
		(property "Value" "SC1KP50V2KX-1GP"
			(at -1.8923 -1.2065 180)
			(unlocked yes)
			(layer "B.Fab")
			(hide yes)
			(effects
				(font
					(size 1.016 1.016)
					(thickness 0.1524)
				)
				(justify mirror)
			)
		)
		(property "Device Type" "C402H22"
			(at -1.8923 -2.7305 180)
			(unlocked yes)
			(layer "B.Fab")
			(hide yes)
			(effects
				(font
					(size 1.016 1.016)
					(thickness 0.1524)
				)
				(justify mirror)
			)
		)
		(duplicate_pad_numbers_are_jumpers no)
		(fp_rect
			(start 0.381 0.7366)
			(end -0.381 -0.7366)
			(stroke
				(width 0)
				(type default)
			)
			(fill no)
			(layer "B.CrtYd")
		)
		(fp_rect
			(start 0.381 0.7366)
			(end -0.381 -0.7366)
			(stroke
				(width 0)
				(type default)
			)
			(fill no)
			(layer "B.Fab")
		)
		(pad "1" smd custom
			(at 0 -0.4572)
			(size 0.1143 0.1143)
			(layers "B.Cu" "B.Mask" "B.Paste")
			(net "GND")
			(options
				(clearance outline)
				(anchor circle)
			)
			(primitives
				(gr_poly
					(pts
						(arc
							(start -0.254 0.1778)
							(mid -0.239121 0.213721)
							(end -0.2032 0.2286)
						)
						(arc
							(start 0.2032 0.2286)
							(mid 0.239121 0.213721)
							(end 0.254 0.1778)
						)
						(arc
							(start 0.254 -0.1778)
							(mid 0.239121 -0.213721)
							(end 0.2032 -0.2286)
						)
						(arc
							(start -0.2032 -0.2286)
							(mid -0.239121 -0.213721)
							(end -0.254 -0.1778)
						)
					)
					(width 0)
					(fill yes)
				)
			)
		)
		(pad "2" smd custom
			(at 0 0.4572)
			(size 0.1143 0.1143)
			(layers "B.Cu" "B.Mask" "B.Paste")
			(net "VR_PVNN_FB_RC2")
			(options
				(clearance outline)
				(anchor circle)
			)
			(primitives
				(gr_poly
					(pts
						(arc
							(start -0.254 0.1778)
							(mid -0.239121 0.213721)
							(end -0.2032 0.2286)
						)
						(arc
							(start 0.2032 0.2286)
							(mid 0.239121 0.213721)
							(end 0.254 0.1778)
						)
						(arc
							(start 0.254 -0.1778)
							(mid 0.239121 -0.213721)
							(end 0.2032 -0.2286)
						)
						(arc
							(start -0.2032 -0.2286)
							(mid -0.239121 -0.213721)
							(end -0.254 -0.1778)
						)
					)
					(width 0)
					(fill yes)
				)
			)
		)
	)
)
